# BASEBOARD_FAB2 (Tioga Pass) — schematic netlist excerpt (pin names and nets, part order shuffled) for the footprints in the layout excerpt that follows; sources: Cadence DE-HDL packaged netlist, KiCad conversion of Wiwynn_Tioga_Pass_MB.brd

R9E13  RES  10.0K 1% CHIP  pkg 0402  page 139 : A = RMII_BMC_PCH_SPRNGVLLE_TXEN ; B = GND
R8C23  RES  0.0 5% EMPTY  pkg 0402  page 118 : A = FM_GBE_LOM_DISABLE_N ; B = FM_10GBE_LOM_DISABLE_N
R8B10  RES  4.75K 1% CHIP  pkg 0402  page 91 : A = PVPP_ABC ; B = IRQ_HFI0_CPU0_LVT2_N

(kicad_pcb
	(version 20260206)
	(generator "pcbnew")
	(generator_version "10.0")
	(general
		(thickness 1.6)
		(legacy_teardrops no)
	)
	(paper "A4")
	(title_block
		(title "Wiwynn_Tioga_Pass_MB.brd")
		(comment 1 "Tioga Pass / footprints 1637-1639 of 4770")
	)
	(layers
		(0 "F.Cu" signal "TOP")
		(4 "In1.Cu" signal "L2GND")
		(6 "In2.Cu" signal "L3")
		(8 "In3.Cu" signal "L4GND")
		(10 "In4.Cu" signal "L5")
		(12 "In5.Cu" signal "L6GND")
		(14 "In6.Cu" signal "L7VCC")
		(16 "In7.Cu" signal "L8VCC")
		(18 "In8.Cu" signal "L9GND")
		(20 "In9.Cu" signal "L10")
		(22 "In10.Cu" signal "L11GND")
		(24 "In11.Cu" signal "L12")
		(26 "In12.Cu" signal "L13GND")
		(2 "B.Cu" signal "BOTTOM")
		(9 "F.Adhes" user "F.Adhesive")
		(11 "B.Adhes" user "B.Adhesive")
		(13 "F.Paste" user "Package Geometry/Pastemask Top")
		(15 "B.Paste" user "Package Geometry/Pastemask Bottom")
		(5 "F.SilkS" user "Ref Des/Silkscreen Top")
		(7 "B.SilkS" user "Ref Des/Silkscreen Bottom")
		(1 "F.Mask" user "Board Geometry/Soldermask Top")
		(3 "B.Mask" user "Board Geometry/Soldermask Bottom")
		(17 "Dwgs.User" user "User.Drawings")
		(19 "Cmts.User" user "User.Comments")
		(21 "Eco1.User" user "User.Eco1")
		(23 "Eco2.User" user "User.Eco2")
		(25 "Edge.Cuts" user "Board Geometry/Outline")
		(27 "Margin" user)
		(31 "F.CrtYd" user "Package Geometry/Place Bound Top")
		(29 "B.CrtYd" user "Package Geometry/Place Bound Bottom")
		(35 "F.Fab" user "Ref Des/Assembly Top")
		(33 "B.Fab" user "Ref Des/Assembly Bottom")
	)
	(footprint ""
		(layer "F.Cu")
		(at 491.0455 -44.0944 90)
		(property "Reference" "R9E13"
			(at 0 0 90)
			(layer "F.SilkS")
			(hide yes)
			(effects
				(font
					(size 1.27 1.27)
				)
			)
		)
		(property "Value" ""
			(at 0 0 90)
			(layer "F.Fab")
			(effects
				(font
					(size 1.27 1.27)
				)
			)
		)
		(duplicate_pad_numbers_are_jumpers no)
		(fp_poly
			(pts
				(xy -0.2794 -0.1016) (xy 0.2794 -0.1016) (xy 0.2794 0.9906) (xy -0.2794 0.9906)
			)
			(stroke
				(width 0)
				(type default)
			)
			(fill no)
			(layer "F.CrtYd")
		)
		(fp_line
			(start 0.2794 -0.1016)
			(end -0.2794 -0.1016)
			(stroke
				(width 0.1)
				(type default)
			)
			(layer "F.Fab")
		)
		(fp_line
			(start -0.2794 -0.1016)
			(end -0.2794 0.9906)
			(stroke
				(width 0.1)
				(type default)
			)
			(layer "F.Fab")
		)
		(fp_line
			(start 0.2794 0.9906)
			(end 0.2794 -0.1016)
			(stroke
				(width 0.1)
				(type default)
			)
			(layer "F.Fab")
		)
		(fp_line
			(start -0.2794 0.9906)
			(end 0.2794 0.9906)
			(stroke
				(width 0.1)
				(type default)
			)
			(layer "F.Fab")
		)
		(pad "1" smd rect
			(at 0 0 90)
			(size 0.508 0.508)
			(layers "F.Cu" "F.Mask" "F.Paste")
			(net "RMII_BMC_PCH_SPRNGVLLE_TXEN")
		)
		(pad "2" smd rect
			(at 0 0.889 90)
			(size 0.508 0.508)
			(layers "F.Cu" "F.Mask" "F.Paste")
			(net "GND")
		)
		(zone
			(layer "F.Cu")
			(hatch none 0.5)
			(connect_pads
				(clearance 0)
			)
			(min_thickness 0.25)
			(keepout
				(tracks allowed)
				(vias not_allowed)
				(pads allowed)
				(copperpour not_allowed)
				(footprints allowed)
			)
			(placement
				(enabled no)
				(sheetname "")
			)
			(fill
				(thermal_gap 0.5)
				(thermal_bridge_width 0.5)
				(island_removal_mode 0)
			)
			(polygon
				(pts
					(xy 491.2995 -43.8404) (xy 491.2995 -44.3484) (xy 491.6805 -44.3484) (xy 491.6805 -43.8404)
				)
			)
		)
		(zone
			(layer "F.Cu")
			(hatch none 0.5)
			(connect_pads
				(clearance 0)
			)
			(min_thickness 0.25)
			(keepout
				(tracks not_allowed)
				(vias allowed)
				(pads allowed)
				(copperpour not_allowed)
				(footprints allowed)
			)
			(placement
				(enabled no)
				(sheetname "")
			)
			(fill
				(thermal_gap 0.5)
				(thermal_bridge_width 0.5)
				(island_removal_mode 0)
			)
			(polygon
				(pts
					(xy 491.6805 -43.8404) (xy 491.6805 -44.3484) (xy 491.2995 -44.3484) (xy 491.2995 -43.8404)
				)
			)
		)
	)
	(footprint ""
		(layer "F.Cu")
		(at 406.7302 -103.7336 -90)
		(property "Reference" "R8C23"
			(at 0 0 270)
			(layer "F.SilkS")
			(hide yes)
			(effects
				(font
					(size 1.27 1.27)
				)
			)
		)
		(property "Value" ""
			(at 0 0 270)
			(layer "F.Fab")
			(effects
				(font
					(size 1.27 1.27)
				)
			)
		)
		(duplicate_pad_numbers_are_jumpers no)
		(fp_poly
			(pts
				(xy -0.2794 -0.1016) (xy 0.2794 -0.1016) (xy 0.2794 0.9906) (xy -0.2794 0.9906)
			)
			(stroke
				(width 0)
				(type default)
			)
			(fill no)
			(layer "F.CrtYd")
		)
		(fp_line
			(start -0.2794 0.9906)
			(end 0.2794 0.9906)
			(stroke
				(width 0.1)
				(type default)
			)
			(layer "F.Fab")
		)
		(fp_line
			(start 0.2794 0.9906)
			(end 0.2794 -0.1016)
			(stroke
				(width 0.1)
				(type default)
			)
			(layer "F.Fab")
		)
		(fp_line
			(start -0.2794 -0.1016)
			(end -0.2794 0.9906)
			(stroke
				(width 0.1)
				(type default)
			)
			(layer "F.Fab")
		)
		(fp_line
			(start 0.2794 -0.1016)
			(end -0.2794 -0.1016)
			(stroke
				(width 0.1)
				(type default)
			)
			(layer "F.Fab")
		)
		(pad "1" smd rect
			(at 0 0 270)
			(size 0.508 0.508)
			(layers "F.Cu" "F.Mask" "F.Paste")
			(net "FM_GBE_LOM_DISABLE_N")
		)
		(pad "2" smd rect
			(at 0 0.889 270)
			(size 0.508 0.508)
			(layers "F.Cu" "F.Mask" "F.Paste")
			(net "FM_10GBE_LOM_DISABLE_N")
		)
		(zone
			(layer "F.Cu")
			(hatch none 0.5)
			(connect_pads
				(clearance 0)
			)
			(min_thickness 0.25)
			(keepout
				(tracks not_allowed)
				(vias allowed)
				(pads allowed)
				(copperpour not_allowed)
				(footprints allowed)
			)
			(placement
				(enabled no)
				(sheetname "")
			)
			(fill
				(thermal_gap 0.5)
				(thermal_bridge_width 0.5)
				(island_removal_mode 0)
			)
			(polygon
				(pts
					(xy 406.0952 -103.9876) (xy 406.0952 -103.4796) (xy 406.4762 -103.4796) (xy 406.4762 -103.9876)
				)
			)
		)
		(zone
			(layer "F.Cu")
			(hatch none 0.5)
			(connect_pads
				(clearance 0)
			)
			(min_thickness 0.25)
			(keepout
				(tracks allowed)
				(vias not_allowed)
				(pads allowed)
				(copperpour not_allowed)
				(footprints allowed)
			)
			(placement
				(enabled no)
				(sheetname "")
			)
			(fill
				(thermal_gap 0.5)
				(thermal_bridge_width 0.5)
				(island_removal_mode 0)
			)
			(polygon
				(pts
					(xy 406.4762 -103.9876) (xy 406.4762 -103.4796) (xy 406.0952 -103.4796) (xy 406.0952 -103.9876)
				)
			)
		)
	)
	(footprint ""
		(layer "F.Cu")
		(at 426.5295 -127.3175 -90)
		(property "Reference" "R8B10"
			(at 0 0 270)
			(layer "F.SilkS")
			(hide yes)
			(effects
				(font
					(size 1.27 1.27)
				)
			)
		)
		(property "Value" ""
			(at 0 0 270)
			(layer "F.Fab")
			(effects
				(font
					(size 1.27 1.27)
				)
			)
		)
		(duplicate_pad_numbers_are_jumpers no)
		(fp_poly
			(pts
				(xy -0.2794 -0.1016) (xy 0.2794 -0.1016) (xy 0.2794 0.9906) (xy -0.2794 0.9906)
			)
			(stroke
				(width 0)
				(type default)
			)
			(fill no)
			(layer "F.CrtYd")
		)
		(fp_line
			(start -0.2794 0.9906)
			(end 0.2794 0.9906)
			(stroke
				(width 0.1)
				(type default)
			)
			(layer "F.Fab")
		)
		(fp_line
			(start 0.2794 0.9906)
			(end 0.2794 -0.1016)
			(stroke
				(width 0.1)
				(type default)
			)
			(layer "F.Fab")
		)
		(fp_line
			(start -0.2794 -0.1016)
			(end -0.2794 0.9906)
			(stroke
				(width 0.1)
				(type default)
			)
			(layer "F.Fab")
		)
		(fp_line
			(start 0.2794 -0.1016)
			(end -0.2794 -0.1016)
			(stroke
				(width 0.1)
				(type default)
			)
			(layer "F.Fab")
		)
		(pad "1" smd rect
			(at 0 0 270)
			(size 0.508 0.508)
			(layers "F.Cu" "F.Mask" "F.Paste")
			(net "PVPP_ABC")
		)
		(pad "2" smd rect
			(at 0 0.889 270)
			(size 0.508 0.508)
			(layers "F.Cu" "F.Mask" "F.Paste")
			(net "IRQ_HFI0_CPU0_LVT2_N")
		)
		(zone
			(layer "F.Cu")
			(hatch none 0.5)
			(connect_pads
				(clearance 0)
			)
			(min_thickness 0.25)
			(keepout
				(tracks not_allowed)
				(vias allowed)
				(pads allowed)
				(copperpour not_allowed)
				(footprints allowed)
			)
			(placement
				(enabled no)
				(sheetname "")
			)
			(fill
				(thermal_gap 0.5)
				(thermal_bridge_width 0.5)
				(island_removal_mode 0)
			)
			(polygon
				(pts
					(xy 425.8945 -127.5715) (xy 425.8945 -127.0635) (xy 426.2755 -127.0635) (xy 426.2755 -127.5715)
				)
			)
		)
		(zone
			(layer "F.Cu")
			(hatch none 0.5)
			(connect_pads
				(clearance 0)
			)
			(min_thickness 0.25)
			(keepout
				(tracks allowed)
				(vias not_allowed)
				(pads allowed)
				(copperpour not_allowed)
				(footprints allowed)
			)
			(placement
				(enabled no)
				(sheetname "")
			)
			(fill
				(thermal_gap 0.5)
				(thermal_bridge_width 0.5)
				(island_removal_mode 0)
			)
			(polygon
				(pts
					(xy 426.2755 -127.5715) (xy 426.2755 -127.0635) (xy 425.8945 -127.0635) (xy 425.8945 -127.5715)
				)
			)
		)
	)
)
